(kicad_pcb
	(version 20241229)
	(generator "pcbnew")
	(generator_version "9.0")
	(general
		(thickness 1.6296)
		(legacy_teardrops no)
	)
	(paper "A3")
	(title_block
		(title "Thunderbolt to 10GbE adapter")
		(date "2026-04-21")
		(rev "1.1.0")
		(company "Antmicro Ltd")
		(comment 1 "www.antmicro.com")
		(comment 9 "footprints 9-12 of 703")
	)
	(layers
		(0 "F.Cu" signal)
		(4 "In1.Cu" signal)
		(6 "In2.Cu" signal)
		(8 "In3.Cu" signal)
		(10 "In4.Cu" signal)
		(12 "In5.Cu" signal)
		(14 "In6.Cu" signal)
		(2 "B.Cu" signal)
		(9 "F.Adhes" user "F.Adhesive")
		(11 "B.Adhes" user "B.Adhesive")
		(13 "F.Paste" user)
		(15 "B.Paste" user)
		(5 "F.SilkS" user "F.Silkscreen")
		(7 "B.SilkS" user "B.Silkscreen")
		(1 "F.Mask" user)
		(3 "B.Mask" user)
		(17 "Dwgs.User" user "User.Drawings")
		(19 "Cmts.User" user "User.Comments")
		(21 "Eco1.User" user "User.Eco1")
		(23 "Eco2.User" user "User.Eco2")
		(25 "Edge.Cuts" user)
		(27 "Margin" user)
		(31 "F.CrtYd" user "F.Courtyard")
		(29 "B.CrtYd" user "B.Courtyard")
		(35 "F.Fab" user)
		(33 "B.Fab" user)
	)
	(footprint "antmicro-footprints:L_Vishay-IHLP1616BZ"
		(layer "F.Cu")
		(at 138.5 124.7 90)
		(property "Reference" "L2"
			(at 1.3 -2.5 90)
			(layer "F.SilkS")
			(effects
				(font
					(size 0.7 0.7)
					(thickness 0.15)
				)
				(justify left bottom)
			)
		)
		(property "Value" "L_680n_7.6A_IHLP1616BZ"
			(at -0.016 3.253 90)
			(layer "F.Fab")
			(effects
				(font
					(size 0.7 0.7)
					(thickness 0.15)
				)
				(justify left bottom)
			)
		)
		(property "Datasheet" "https://www.mouser.com/datasheet/2/427/ihlp1616bz5a-1763007.pdf"
			(at 0 0 90)
			(layer "F.Fab")
			(hide yes)
			(effects
				(font
					(size 1.27 1.27)
					(thickness 0.15)
				)
			)
		)
		(property "Description" "Power Inductor (SMT), 680 nH, 7.6 A, Shielded, 6.8 A, IHLP-1616BZ-5A"
			(at 0 0 90)
			(layer "F.Fab")
			(hide yes)
			(effects
				(font
					(size 1.27 1.27)
					(thickness 0.15)
				)
			)
		)
		(property "Val" "680n/7.6A"
			(at 0 0 90)
			(unlocked yes)
			(layer "F.Fab")
			(hide yes)
			(effects
				(font
					(size 1 1)
					(thickness 0.15)
				)
			)
		)
		(property "Manufacturer" "Vishay"
			(at 0 0 90)
			(unlocked yes)
			(layer "F.Fab")
			(hide yes)
			(effects
				(font
					(size 1 1)
					(thickness 0.15)
				)
			)
		)
		(property "MPN" "IHLP1616BZERR68M5A"
			(at 0 0 90)
			(unlocked yes)
			(layer "F.Fab")
			(hide yes)
			(effects
				(font
					(size 1 1)
					(thickness 0.15)
				)
			)
		)
		(property "ISat" "6.8 A"
			(at 0 0 90)
			(unlocked yes)
			(layer "F.Fab")
			(hide yes)
			(effects
				(font
					(size 1 1)
					(thickness 0.15)
				)
			)
		)
		(property "IMax" "7.6 A"
			(at 0 0 90)
			(unlocked yes)
			(layer "F.Fab")
			(hide yes)
			(effects
				(font
					(size 1 1)
					(thickness 0.15)
				)
			)
		)
		(property "Size" "4.06x4.06"
			(at 0 0 90)
			(unlocked yes)
			(layer "F.Fab")
			(hide yes)
			(effects
				(font
					(size 1 1)
					(thickness 0.15)
				)
			)
		)
		(property "Author" "Antmicro"
			(at 0 0 90)
			(unlocked yes)
			(layer "F.Fab")
			(hide yes)
			(effects
				(font
					(size 1 1)
					(thickness 0.15)
				)
			)
		)
		(property "License" "Apache-2.0"
			(at 0 0 90)
			(unlocked yes)
			(layer "F.Fab")
			(hide yes)
			(effects
				(font
					(size 1 1)
					(thickness 0.15)
				)
			)
		)
		(sheetname "/TB Controller - Power/")
		(sheetfile "tb-power.kicad_sch")
		(attr smd)
		(fp_line
			(start 2.012 -2.024)
			(end -2.044 -2.024)
			(stroke
				(width 0.15)
				(type solid)
			)
			(layer "F.SilkS")
		)
		(fp_line
			(start 2.012 -2.024)
			(end 2.012 -1.45)
			(stroke
				(width 0.15)
				(type solid)
			)
			(layer "F.SilkS")
		)
		(fp_line
			(start -2.044 -2.024)
			(end -2.044 -1.45)
			(stroke
				(width 0.15)
				(type solid)
			)
			(layer "F.SilkS")
		)
		(fp_line
			(start 2.012 2.031)
			(end 2.012 1.45)
			(stroke
				(width 0.15)
				(type solid)
			)
			(layer "F.SilkS")
		)
		(fp_line
			(start -2.044 2.031)
			(end -2.044 1.45)
			(stroke
				(width 0.15)
				(type solid)
			)
			(layer "F.SilkS")
		)
		(fp_line
			(start -2.044 2.031)
			(end 2.012 2.031)
			(stroke
				(width 0.15)
				(type solid)
			)
			(layer "F.SilkS")
		)
		(fp_line
			(start -2.475 -2.31)
			(end 2.475 -2.31)
			(stroke
				(width 0.05)
				(type solid)
			)
			(layer "F.CrtYd")
		)
		(fp_line
			(start 2.475 -1.4)
			(end 2.475 -2.31)
			(stroke
				(width 0.05)
				(type solid)
			)
			(layer "F.CrtYd")
		)
		(fp_line
			(start 2.475 -1.4)
			(end 3.07 -1.4)
			(stroke
				(width 0.05)
				(type solid)
			)
			(layer "F.CrtYd")
		)
		(fp_line
			(start -2.475 -1.4)
			(end -2.475 -2.31)
			(stroke
				(width 0.05)
				(type solid)
			)
			(layer "F.CrtYd")
		)
		(fp_line
			(start -2.475 -1.4)
			(end -3.07 -1.4)
			(stroke
				(width 0.05)
				(type solid)
			)
			(layer "F.CrtYd")
		)
		(fp_line
			(start 3.07 1.4)
			(end 3.07 -1.4)
			(stroke
				(width 0.05)
				(type solid)
			)
			(layer "F.CrtYd")
		)
		(fp_line
			(start 2.475 1.4)
			(end 3.07 1.4)
			(stroke
				(width 0.05)
				(type solid)
			)
			(layer "F.CrtYd")
		)
		(fp_line
			(start 2.475 1.4)
			(end 2.475 2.32)
			(stroke
				(width 0.05)
				(type solid)
			)
			(layer "F.CrtYd")
		)
		(fp_line
			(start -2.475 1.4)
			(end -3.07 1.4)
			(stroke
				(width 0.05)
				(type solid)
			)
			(layer "F.CrtYd")
		)
		(fp_line
			(start -2.475 1.4)
			(end -2.475 2.32)
			(stroke
				(width 0.05)
				(type solid)
			)
			(layer "F.CrtYd")
		)
		(fp_line
			(start -3.07 1.4)
			(end -3.07 -1.4)
			(stroke
				(width 0.05)
				(type solid)
			)
			(layer "F.CrtYd")
		)
		(fp_line
			(start -2.475 2.32)
			(end 2.475 2.32)
			(stroke
				(width 0.05)
				(type solid)
			)
			(layer "F.CrtYd")
		)
		(fp_rect
			(start -2.217 -2.065)
			(end 2.217 2.064)
			(stroke
				(width 0.15)
				(type solid)
			)
			(fill no)
			(layer "F.Fab")
		)
		(fp_text user "Author: Antmicro"
			(at -3.07 5.253 90)
			(layer "F.Fab")
			(effects
				(font
					(size 0.7 0.7)
					(thickness 0.15)
				)
				(justify left bottom)
			)
		)
		(fp_text user "${REFERENCE}"
			(at -3.07 7.653 90)
			(layer "F.Fab")
			(effects
				(font
					(size 0.7 0.7)
					(thickness 0.15)
				)
				(justify left bottom)
			)
		)
		(fp_text user "License: Apache-2.0"
			(at -3.07 6.453 90)
			(layer "F.Fab")
			(effects
				(font
					(size 0.7 0.7)
					(thickness 0.15)
				)
				(justify left bottom)
			)
		)
		(pad "1" smd roundrect
			(at -1.89225 0 180)
			(size 2.286 1.8545)
			(layers "F.Cu" "F.Mask" "F.Paste")
			(roundrect_rratio 0.1)
			(net 426 "Net-(L2-Pad1)")
			(pintype "passive")
		)
		(pad "2" smd roundrect
			(at 1.89225 0 180)
			(size 2.286 1.8545)
			(layers "F.Cu" "F.Mask" "F.Paste")
			(roundrect_rratio 0.1)
			(net 68 "/TB Controller - Power/VCC_0P9")
			(pintype "passive")
		)
	)
	(footprint "antmicro-footprints:L_Bourns-SRP4021HMT"
		(layer "F.Cu")
		(at 162.549999 106.000001 -90)
		(property "Reference" "L7"
			(at 17.549996 -12.450003 270)
			(layer "F.SilkS")
			(effects
				(font
					(size 0.7 0.7)
					(thickness 0.15)
				)
			)
		)
		(property "Value" "L_1u_10A_Bourns-SRP4021HMT"
			(at -2.85 3.4 270)
			(layer "F.Fab")
			(effects
				(font
					(size 0.7 0.7)
					(thickness 0.15)
				)
				(justify left bottom)
			)
		)
		(property "Datasheet" "https://www.mouser.com/datasheet/2/54/Bourns_04_01_2025_SRP4021HMT_Datasheet-3580094.pdf"
			(at 0 0 270)
			(layer "F.Fab")
			(effects
				(font
					(size 0.7 0.7)
					(thickness 0.15)
				)
				(justify left bottom)
			)
		)
		(property "Description" "Power Inductors - SMD Ind,4.1x4.2x1.9mm,1uH+/-20%,10A, Shielded"
			(at 0 0 270)
			(layer "F.Fab")
			(effects
				(font
					(size 0.7 0.7)
					(thickness 0.15)
				)
				(justify left bottom)
			)
		)
		(property "Val" "1u/10A"
			(at 0 0 270)
			(unlocked yes)
			(layer "F.Fab")
			(hide yes)
			(effects
				(font
					(size 1 1)
					(thickness 0.15)
				)
			)
		)
		(property "Manufacturer" "Bourns"
			(at 0 0 270)
			(unlocked yes)
			(layer "F.Fab")
			(hide yes)
			(effects
				(font
					(size 1 1)
					(thickness 0.15)
				)
			)
		)
		(property "MPN" "SRP4021HMT-1R0M"
			(at 0 0 270)
			(unlocked yes)
			(layer "F.Fab")
			(hide yes)
			(effects
				(font
					(size 1 1)
					(thickness 0.15)
				)
			)
		)
		(property "ISat" ""
			(at 0 0 270)
			(unlocked yes)
			(layer "F.Fab")
			(hide yes)
			(effects
				(font
					(size 1 1)
					(thickness 0.15)
				)
			)
		)
		(property "Isat" "8A"
			(at 0 0 270)
			(unlocked yes)
			(layer "F.Fab")
			(hide yes)
			(effects
				(font
					(size 1 1)
					(thickness 0.15)
				)
			)
		)
		(property "IMax" ""
			(at 0 0 270)
			(unlocked yes)
			(layer "F.Fab")
			(hide yes)
			(effects
				(font
					(size 1 1)
					(thickness 0.15)
				)
			)
		)
		(property "Imax" "10A"
			(at 0 0 270)
			(unlocked yes)
			(layer "F.Fab")
			(hide yes)
			(effects
				(font
					(size 1 1)
					(thickness 0.15)
				)
			)
		)
		(property "Size" "4.2x4.1"
			(at 0 0 270)
			(unlocked yes)
			(layer "F.Fab")
			(hide yes)
			(effects
				(font
					(size 1 1)
					(thickness 0.15)
				)
			)
		)
		(property "Author" "Antmicro"
			(at 0 0 270)
			(unlocked yes)
			(layer "F.Fab")
			(hide yes)
			(effects
				(font
					(size 1 1)
					(thickness 0.15)
				)
			)
		)
		(property "License" "Apache-2.0"
			(at 0 0 270)
			(unlocked yes)
			(layer "F.Fab")
			(hide yes)
			(effects
				(font
					(size 1 1)
					(thickness 0.15)
				)
			)
		)
		(sheetname "/X710 DCDC converters/")
		(sheetfile "DCDC_converters_X710.kicad_sch")
		(attr smd)
		(fp_line
			(start -0.8 2.05)
			(end 0.8 2.05)
			(stroke
				(width 0.15)
				(type solid)
			)
			(layer "F.SilkS")
		)
		(fp_line
			(start -0.8 -2.05)
			(end 0.8 -2.05)
			(stroke
				(width 0.15)
				(type solid)
			)
			(layer "F.SilkS")
		)
		(fp_rect
			(start -2.85 -2.3)
			(end 2.85 2.3)
			(stroke
				(width 0.05)
				(type solid)
			)
			(fill no)
			(layer "F.CrtYd")
		)
		(fp_rect
			(start -2 -2.05)
			(end 2 2.05)
			(stroke
				(width 0.15)
				(type solid)
			)
			(fill no)
			(layer "F.Fab")
		)
		(fp_text user "Author: Antmicro"
			(at -2.85 4.6 270)
			(layer "F.Fab")
			(effects
				(font
					(size 0.7 0.7)
					(thickness 0.15)
				)
				(justify left bottom)
			)
		)
		(fp_text user "License: Apache-2.0"
			(at -2.85 7 270)
			(layer "F.Fab")
			(effects
				(font
					(size 0.7 0.7)
					(thickness 0.15)
				)
				(justify left bottom)
			)
		)
		(fp_text user "${REFERENCE}"
			(at -2.85 5.8 270)
			(layer "F.Fab")
			(effects
				(font
					(size 0.7 0.7)
					(thickness 0.15)
				)
				(justify left bottom)
			)
		)
		(pad "1" smd rect
			(at 1.85 0 90)
			(size 1.5 3.5)
			(layers "F.Cu" "F.Mask" "F.Paste")
			(net 310 "/X710 DCDC converters/1V0_SW")
			(pintype "passive")
		)
		(pad "2" smd rect
			(at -1.85 0 90)
			(size 1.5 3.5)
			(layers "F.Cu" "F.Mask" "F.Paste")
			(net 339 "/X710 DCDC converters/+1V0_OUT")
			(pintype "passive")
		)
	)
	(footprint "antmicro-footprints:R_0402_1005Metric"
		(layer "F.Cu")
		(at 124 71 180)
		(descr "Resistor SMD 0402")
		(tags "resistor SMD 0402")
		(property "Reference" "R221"
			(at -1 0.2 180)
			(layer "F.SilkS")
			(effects
				(font
					(size 0.7 0.7)
					(thickness 0.15)
				)
				(justify left bottom)
			)
		)
		(property "Value" "R_0R_0402"
			(at -1.011843 1.772047 180)
			(layer "F.Fab")
			(effects
				(font
					(size 0.7 0.7)
					(thickness 0.15)
				)
				(justify left bottom)
			)
		)
		(property "Datasheet" "https://industrial.panasonic.com/cdbs/www-data/pdf/RDA0000/AOA0000C301.pdf"
			(at 0 0 180)
			(layer "F.Fab")
			(hide yes)
			(effects
				(font
					(size 1.27 1.27)
					(thickness 0.15)
				)
			)
		)
		(property "Description" "SMD Chip Resistor, Jumper, 0 ohm, 100 mW, 0402 [1005 Metric], Thick Film, General Purpose"
			(at 0 0 180)
			(layer "F.Fab")
			(hide yes)
			(effects
				(font
					(size 1.27 1.27)
					(thickness 0.15)
				)
			)
		)
		(property "MPN" "ERJ2GE0R00X"
			(at 0 0 180)
			(unlocked yes)
			(layer "F.Fab")
			(hide yes)
			(effects
				(font
					(size 1 1)
					(thickness 0.15)
				)
			)
		)
		(property "Manufacturer" "Panasonic"
			(at 0 0 180)
			(unlocked yes)
			(layer "F.Fab")
			(hide yes)
			(effects
				(font
					(size 1 1)
					(thickness 0.15)
				)
			)
		)
		(property "License" "Apache-2.0"
			(at 0 0 180)
			(unlocked yes)
			(layer "F.Fab")
			(hide yes)
			(effects
				(font
					(size 1 1)
					(thickness 0.15)
				)
			)
		)
		(property "Author" "Antmicro"
			(at 0 0 180)
			(unlocked yes)
			(layer "F.Fab")
			(hide yes)
			(effects
				(font
					(size 1 1)
					(thickness 0.15)
				)
			)
		)
		(property "Val" "0R"
			(at 0 0 180)
			(unlocked yes)
			(layer "F.Fab")
			(hide yes)
			(effects
				(font
					(size 1 1)
					(thickness 0.15)
				)
			)
		)
		(property "Tolerance" "~"
			(at 0 0 180)
			(unlocked yes)
			(layer "F.Fab")
			(hide yes)
			(effects
				(font
					(size 1 1)
					(thickness 0.15)
				)
			)
		)
		(property "Current" "1A"
			(at 0 0 180)
			(unlocked yes)
			(layer "F.Fab")
			(hide yes)
			(effects
				(font
					(size 1 1)
					(thickness 0.15)
				)
			)
		)
		(sheetname "/Fan controller/")
		(sheetfile "fan-controller.kicad_sch")
		(attr smd)
		(fp_rect
			(start -0.925 -0.47)
			(end 0.925 0.47)
			(stroke
				(width 0.05)
				(type default)
			)
			(fill no)
			(layer "F.CrtYd")
		)
		(fp_rect
			(start -0.5 -0.25)
			(end 0.5 0.25)
			(stroke
				(width 0.15)
				(type solid)
			)
			(fill no)
			(layer "F.Fab")
		)
		(fp_text user "Author: Antmicro"
			(at -0.95 4.169 180)
			(layer "F.Fab")
			(effects
				(font
					(size 0.7 0.7)
					(thickness 0.15)
				)
				(justify left bottom)
			)
		)
		(fp_text user "License: Apache-2.0"
			(at -0.95 5.169 180)
			(layer "F.Fab")
			(effects
				(font
					(size 0.7 0.7)
					(thickness 0.15)
				)
				(justify left bottom)
			)
		)
		(fp_text user "${REFERENCE}"
			(at -0.95 3.168 180)
			(layer "F.Fab")
			(effects
				(font
					(size 0.7 0.7)
					(thickness 0.15)
				)
				(justify left bottom)
			)
		)
		(pad "1" smd roundrect
			(at -0.48 0 180)
			(size 0.59 0.64)
			(layers "F.Cu" "F.Mask" "F.Paste")
			(roundrect_rratio 0.25)
			(net 23 "GND")
			(pintype "passive")
		)
		(pad "2" smd roundrect
			(at 0.48 0 180)
			(size 0.59 0.64)
			(layers "F.Cu" "F.Mask" "F.Paste")
			(roundrect_rratio 0.25)
			(net 156 "/Fan controller/D0")
			(pintype "passive")
		)
	)
	(footprint "antmicro-footprints:R_0402_1005Metric"
		(layer "F.Cu")
		(at 157.355 94.055 90)
		(descr "Resistor SMD 0402")
		(tags "resistor SMD 0402")
		(property "Reference" "R165"
			(at -19.145001 23.294999 90)
			(layer "F.SilkS")
			(effects
				(font
					(size 0.7 0.7)
					(thickness 0.15)
				)
			)
		)
		(property "Value" "R_10R_0402"
			(at -1.011843 1.772047 90)
			(layer "F.Fab")
			(effects
				(font
					(size 0.7 0.7)
					(thickness 0.15)
				)
				(justify left bottom)
			)
		)
		(property "Datasheet" "https://www.bourns.com/docs/product-datasheets/cr.pdf"
			(at 0 0 90)
			(layer "F.Fab")
			(hide yes)
			(effects
				(font
					(size 1.27 1.27)
					(thickness 0.15)
				)
			)
		)
		(property "Description" "SMD Chip Resistor, 10 ohm, ± 1%, 62.5 mW, 0402 [1005 Metric], Thick Film, General Purpose"
			(at 0 0 90)
			(layer "F.Fab")
			(hide yes)
			(effects
				(font
					(size 1.27 1.27)
					(thickness 0.15)
				)
			)
		)
		(property "MPN" "CR0402-FX-10R0GLF"
			(at 0 0 90)
			(unlocked yes)
			(layer "F.Fab")
			(hide yes)
			(effects
				(font
					(size 1 1)
					(thickness 0.15)
				)
			)
		)
		(property "Manufacturer" "Bourns"
			(at 0 0 90)
			(unlocked yes)
			(layer "F.Fab")
			(hide yes)
			(effects
				(font
					(size 1 1)
					(thickness 0.15)
				)
			)
		)
		(property "License" "Apache-2.0"
			(at 0 0 90)
			(unlocked yes)
			(layer "F.Fab")
			(hide yes)
			(effects
				(font
					(size 1 1)
					(thickness 0.15)
				)
			)
		)
		(property "Author" "Antmicro"
			(at 0 0 90)
			(unlocked yes)
			(layer "F.Fab")
			(hide yes)
			(effects
				(font
					(size 1 1)
					(thickness 0.15)
				)
			)
		)
		(property "Val" "10R"
			(at 0 0 90)
			(unlocked yes)
			(layer "F.Fab")
			(hide yes)
			(effects
				(font
					(size 1 1)
					(thickness 0.15)
				)
			)
		)
		(property "Tolerance" "1%"
			(at 0 0 90)
			(unlocked yes)
			(layer "F.Fab")
			(hide yes)
			(effects
				(font
					(size 1 1)
					(thickness 0.15)
				)
			)
		)
		(sheetname "/X710-AT2 Misc/")
		(sheetfile "x710-at2-mics.kicad_sch")
		(attr smd)
		(fp_rect
			(start -0.925 -0.47)
			(end 0.925 0.47)
			(stroke
				(width 0.05)
				(type default)
			)
			(fill no)
			(layer "F.CrtYd")
		)
		(fp_rect
			(start -0.5 -0.25)
			(end 0.5 0.25)
			(stroke
				(width 0.15)
				(type solid)
			)
			(fill no)
			(layer "F.Fab")
		)
		(fp_text user "Author: Antmicro"
			(at -0.95 4.169 90)
			(layer "F.Fab")
			(effects
				(font
					(size 0.7 0.7)
					(thickness 0.15)
				)
				(justify left bottom)
			)
		)
		(fp_text user "License: Apache-2.0"
			(at -0.95 5.169 90)
			(layer "F.Fab")
			(effects
				(font
					(size 0.7 0.7)
					(thickness 0.15)
				)
				(justify left bottom)
			)
		)
		(fp_text user "${REFERENCE}"
			(at -0.95 3.168 90)
			(layer "F.Fab")
			(effects
				(font
					(size 0.7 0.7)
					(thickness 0.15)
				)
				(justify left bottom)
			)
		)
		(pad "1" smd roundrect
			(at -0.48 0 90)
			(size 0.59 0.64)
			(layers "F.Cu" "F.Mask" "F.Paste")
			(roundrect_rratio 0.25)
			(net 59 "/X710-AT2 Misc/50MHZ_XTAL_R.-")
			(pintype "passive")
		)
		(pad "2" smd roundrect
			(at 0.48 0 90)
			(size 0.59 0.64)
			(layers "F.Cu" "F.Mask" "F.Paste")
			(roundrect_rratio 0.25)
			(net 120 "/X710-AT2 Misc/50MHZ_XTAL.-")
			(pintype "passive")
		)
	)
)
